# BASEBOARD_FAB2 (Tioga Pass) — schematic parts with pin connectivity, parts 4665–4675 of 4751; source: Cadence DE-HDL packaged netlist (pstxprt.dat, pstxnet.dat, pstchip.dat)

U5D1  SKX_EXT_B  IC  pkg BGA1  page 21  (pins 3391-3647 of 3647)
  P83  VSS(1022)  GROUND  = GND
  P85  DDR0_DQS_DP(1)  BI  = M_A_DQS_DP<1>
  R2  VSS(1019)  GROUND  = GND
  R4  VSS(1018)  GROUND  = GND
  R6  UPI1_RX_DP(0)  IN  = UPI_CPU1_CPU0_P1P1_DP<19>
  R8  UPI1_RX_DP(3)  IN  = UPI_CPU1_CPU0_P1P1_DP<16>
  R10  UPI1_RX_DN(5)  IN  = UPI_CPU1_CPU0_P1P1_DN<14>
  R12  UPI1_RX_DN(9)  IN  = UPI_CPU1_CPU0_P1P1_DN<10>
  R14  VSS(1021)  GROUND  = GND
  R16  UPI1_RX_DN(10)  IN  = UPI_CPU1_CPU0_P1P1_DN<9>
  R18  VSS(1020)  GROUND  = GND
  R20  UPI1_RX_DN(14)  IN  = UPI_CPU1_CPU0_P1P1_DN<5>
  R22  VSS(1017)  GROUND  = GND
  R24  DDR0_DQS_DP(7)  BI  = M_A_DQS_DP<7>
  R26  VSS(1016)  GROUND  = GND
  R28  VSS(1015)  GROUND  = GND
  R30  DDR0_DQS_DN(6)  BI  = M_A_DQS_DN<6>
  R32  VSS(1014)  GROUND  = GND
  R34  VSS(1013)  GROUND  = GND
  R36  DDR0_DQS_DN(5)  BI  = M_A_DQS_DN<5>
  R38  VSS(1012)  GROUND  = GND
  R40  VSS(1011)  GROUND  = GND
  R42  DDR1_DQS_DP(4)  BI  = M_B_DQS_DP<4>
  R46  DDR1_CS_N(7)  OUT  = M_B_CS_N<7>
  R48  DDR1_ODT(1)  OUT  = M_B_ODT<1>
  R50  DDR1_CS_N(1)  OUT  = M_B_CS_N<1>
  R52  DDR1_MA(16)  OUT  = M_B_MA<16>
  R54  DDR1_CLK_DN(1)  OUT  = M_B_CLK_DN<1>
  R56  DDR1_CLK_DN(3)  OUT  = M_B_CLK_DN<3>
  R58  DDR1_MA(5)  OUT  = M_B_MA<5>
  R60  DDR1_MA(11)  OUT  = M_B_MA<11>
  R62  RSVD(264)  BI  = TP_CPU0_RSVD_264
  R64  DDR1_CKE(1)  OUT  = M_B_CKE<1>
  R66  RSVD(263)  BI  = TP_CPU0_RSVD_263
  R68  VSS(1010)  GROUND  = GND
  R70  DDR2_DQ(18)  BI  = M_C_DQ<18>
  R72  VSS(1009)  GROUND  = GND
  R74  DDR0_DQ(31)  BI  = M_A_DQ<31>
  R76  DDR0_DQ(25)  BI  = M_A_DQ<25>
  R78  VSS(1008)  GROUND  = GND
  R80  DDR0_DQS_DP(2)  BI  = M_A_DQS_DP<2>
  R82  DDR0_DQ(22)  BI  = M_A_DQ<22>
  R84  DDR0_DQS_DN(1)  BI  = M_A_DQS_DN<1>
  R86  VSS(1007)  GROUND  = GND
  T1  UPI0_TX_DP(1)  OUT  = UPI_CPU0_CPU1_P0P0_DP<18>
  T3  VCCIO(50)  POWER  = PVCCIO_CPU0
  T5  UPI1_RX_DN(0)  IN  = UPI_CPU1_CPU0_P1P1_DN<19>
  T7  UPI1_RX_DP(1)  IN  = UPI_CPU1_CPU0_P1P1_DP<18>
  T9  UPI1_RX_DN(3)  IN  = UPI_CPU1_CPU0_P1P1_DN<16>
  T11  UPI1_RX_DP(6)  IN  = UPI_CPU1_CPU0_P1P1_DP<13>
  T13  VSS(1006)  GROUND  = GND
  T15  UPI1_RX_DP(10)  IN  = UPI_CPU1_CPU0_P1P1_DP<9>
  T17  VSS(1005)  GROUND  = GND
  T19  UPI1_RX_DP(15)  IN  = UPI_CPU1_CPU0_P1P1_DP<4>
  T21  UPI1_RX_DP(16)  IN  = UPI_CPU1_CPU0_P1P1_DP<3>
  T23  DDR0_DQ(59)  BI  = M_A_DQ<59>
  T25  VSS(1004)  GROUND  = GND
  T27  DDR1_DQS_DN(16)  BI  = M_B_DQS_DN<16>
  T29  VSS(1003)  GROUND  = GND
  T31  VSS(1002)  GROUND  = GND
  T33  DDR2_DQS_DN(14)  BI  = M_C_DQS_DN<14>
  T35  VSS(1001)  GROUND  = GND
  T37  VSS(1000)  GROUND  = GND
  T39  DDR2_DQS_DN(13)  BI  = M_C_DQS_DN<13>
  T41  VSS(999)  GROUND  = GND
  T43  DDR1_DQ(37)  BI  = M_B_DQ<37>
  T45  DDR2_CS_N(6)  OUT  = M_C_CS_N<6>
  T47  DDR1_ODT(3)  OUT  = M_B_ODT<3>
  T49  DDR1_CS_N(5)  OUT  = M_B_CS_N<5>
  T51  DDR1_MA(14)  OUT  = M_B_MA<14>
  T53  DDR1_BA(0)  OUT  = M_B_BA<0>
  T55  DDR1_CLK_DP(1)  OUT  = M_B_CLK_DP<1>
  T57  DDR1_CLK_DP(3)  OUT  = M_B_CLK_DP<3>
  T59  DDR1_MA(6)  OUT  = M_B_MA<6>
  T61  DDR1_MA(12)  OUT  = M_B_MA<12>
  T63  DDR1_ACT_N  OUT  = M_B_ACT_N
  T65  VSS(998)  GROUND  = GND
  T67  RSVD(262)  BI  = TP_CPU0_RSVD_262
  T69  DDR2_DQ(19)  BI  = M_C_DQ<19>
  T71  DDR2_DQ(22)  BI  = M_C_DQ<22>
  T73  VSS(997)  GROUND  = GND
  T75  DDR0_DQS_DN(3)  BI  = M_A_DQS_DN<3>
  T77  VSS(996)  GROUND  = GND
  T79  DDR0_DQ(17)  BI  = M_A_DQ<17>
  T81  DDR0_DQS_DP(11)  BI  = M_A_DQS_DP<11>
  T83  VSS(995)  GROUND  = GND
  T85  VSS(994)  GROUND  = GND
  U2  VSS(993)  GROUND  = GND
  U4  VSS(992)  GROUND  = GND
  U6  VSS(991)  GROUND  = GND
  U8  UPI1_RX_DP(2)  IN  = UPI_CPU1_CPU0_P1P1_DP<17>
  U10  UPI1_RX_DP(5)  IN  = UPI_CPU1_CPU0_P1P1_DP<14>
  U12  UPI1_RX_DN(6)  IN  = UPI_CPU1_CPU0_P1P1_DN<13>
  U14  VCCIO(49)  POWER  = PVCCIO_CPU0
  U16  UPI1_RX_DN(12)  IN  = UPI_CPU1_CPU0_P1P1_DN<7>
  U18  UPI1_RX_DN(15)  IN  = UPI_CPU1_CPU0_P1P1_DN<4>
  U20  VSS(990)  GROUND  = GND
  U22  VSS(989)  GROUND  = GND
  U24  VSS(988)  GROUND  = GND
  U26  DDR1_DQ(62)  BI  = M_B_DQ<62>
  U28  DDR1_DQ(56)  BI  = M_B_DQ<56>
  U30  VSS(987)  GROUND  = GND
  U32  DDR2_DQ(46)  BI  = M_C_DQ<46>
  U34  DDR2_DQ(40)  BI  = M_C_DQ<40>
  U36  VSS(986)  GROUND  = GND
  U38  DDR2_DQ(38)  BI  = M_C_DQ<38>
  U40  DDR2_DQ(32)  BI  = M_C_DQ<32>
  U42  VSS(985)  GROUND  = GND
  U46  VCCD012(23)  POWER  = PVDDQ_ABC
  U48  VCCD012(24)  POWER  = PVDDQ_ABC
  U50  VCCD012(25)  POWER  = PVDDQ_ABC
  U52  VCCD012(26)  POWER  = PVDDQ_ABC
  U54  VCCD012(27)  POWER  = PVDDQ_ABC
  U56  VCCD012(28)  POWER  = PVDDQ_ABC
  U58  VCCD012(29)  POWER  = PVDDQ_ABC
  U60  VCCD012(30)  POWER  = PVDDQ_ABC
  U62  VCCD012(31)  POWER  = PVDDQ_ABC
  U64  DDR012_RESET_N  OUT  = M_ABC_RST_N
  U66  RSVD(261)  BI  = TP_CPU0_RSVD_261
  U68  VSS(984)  GROUND  = GND
  U70  VSS(983)  GROUND  = GND
  U72  DDR2_DQS_DN(11)  BI  = M_C_DQS_DN<11>
  U74  VSS(982)  GROUND  = GND
  U76  VSS(981)  GROUND  = GND
  U78  VSS(980)  GROUND  = GND
  U80  VSS(979)  GROUND  = GND
  U82  DDR0_DQS_DN(11)  BI  = M_A_DQS_DN<11>
  U84  DDR0_DQS_DN(10)  BI  = M_A_DQS_DN<10>
  U86  VSS(978)  GROUND  = GND
  V1  VSS(977)  GROUND  = GND
  V3  UPI0_TX_DN(2)  OUT  = UPI_CPU0_CPU1_P0P0_DN<17>
  V5  VSS(976)  GROUND  = GND
  V7  UPI1_RX_DN(2)  IN  = UPI_CPU1_CPU0_P1P1_DN<17>
  V9  VSS(975)  GROUND  = GND
  V11  VSS(1227)  GROUND  = GND
  V13  VSS(974)  GROUND  = GND
  V15  VSS(973)  GROUND  = GND
  V17  UPI1_RX_DP(13)  IN  = UPI_CPU1_CPU0_P1P1_DP<6>
  V19  UPI1_RX_DN(17)  IN  = UPI_CPU1_CPU0_P1P1_DN<2>
  V21  VSS(972)  GROUND  = GND
  V23  VSS(971)  GROUND  = GND
  V25  DDR1_DQ(58)  BI  = M_B_DQ<58>
  V27  DDR1_DQS_DP(16)  BI  = M_B_DQS_DP<16>
  V29  DDR1_DQ(60)  BI  = M_B_DQ<60>
  V31  DDR2_DQ(42)  BI  = M_C_DQ<42>
  V33  DDR2_DQS_DP(14)  BI  = M_C_DQS_DP<14>
  V35  DDR2_DQ(44)  BI  = M_C_DQ<44>
  V37  DDR2_DQ(34)  BI  = M_C_DQ<34>
  V39  DDR2_DQS_DP(13)  BI  = M_C_DQS_DP<13>
  V41  DDR2_DQ(36)  BI  = M_C_DQ<36>
  V43  VSS(970)  GROUND  = GND
  V45  DDR2_CS_N(7)  OUT  = M_C_CS_N<7>
  V47  DDR1_CS_N(3)  OUT  = M_B_CS_N<3>
  V49  DDR2_ODT(2)  OUT  = M_C_ODT<2>
  V51  DDR2_CS_N(0)  OUT  = M_C_CS_N<0>
  V53  DDR2_PAR  OUT  = M_C_PAR
  V55  DDR2_CLK_DP(1)  OUT  = M_C_CLK_DP<1>
  V57  DDR2_CLK_DP(3)  OUT  = M_C_CLK_DP<3>
  V59  DDR2_MA(5)  OUT  = M_C_MA<5>
  V61  DDR1_MA(7)  OUT  = M_B_MA<7>
  V63  DDR2_CKE(2)  OUT  = M_C_CKE<2>
  V65  RSVD(260)  BI  = TP_CPU0_RSVD_260
  V67  RSVD(259)  BI  = TP_CPU0_RSVD_259
  V69  DDR2_DQ(23)  BI  = M_C_DQ<23>
  V71  DDR2_DQS_DP(11)  BI  = M_C_DQS_DP<11>
  V73  VSS(969)  GROUND  = GND
  V75  VSS(968)  GROUND  = GND
  V77  VSS(967)  GROUND  = GND
  V79  DDR0_DQ(21)  BI  = M_A_DQ<21>
  V81  DDR0_DQ(16)  BI  = M_A_DQ<16>
  V83  VSS(966)  GROUND  = GND
  V85  DDR0_DQS_DP(10)  BI  = M_A_DQS_DP<10>
  W2  UPI0_TX_DP(3)  OUT  = UPI_CPU0_CPU1_P0P0_DP<16>
  W4  VCCIO(47)  POWER  = PVCCIO_CPU0
  W6  VCCIO(46)  POWER  = PVCCIO_CPU0
  W8  VSS(965)  GROUND  = GND
  W10  VCCIO(74)  POWER  = PVCCIO_CPU0
  W12  VSS(963)  GROUND  = GND
  W14  TMS  IN  = XDP_CPU_TMS
  W16  UPI1_RX_DP(12)  IN  = UPI_CPU1_CPU0_P1P1_DP<7>
  W18  UPI1_RX_DN(13)  IN  = UPI_CPU1_CPU0_P1P1_DN<6>
  W20  UPI1_RX_DP(18)  IN  = UPI_CPU1_CPU0_P1P1_DP<1>
  W22  VSS(962)  GROUND  = GND
  W24  VSS(961)  GROUND  = GND
  W26  VSS(960)  GROUND  = GND
  W28  VSS(959)  GROUND  = GND
  W30  VSS(958)  GROUND  = GND
  W32  VSS(957)  GROUND  = GND
  W34  VSS(956)  GROUND  = GND
  W36  VSS(955)  GROUND  = GND
  W38  VSS(954)  GROUND  = GND
  W40  VSS(953)  GROUND  = GND
  W42  VSS(952)  GROUND  = GND
  W46  DDR2_CS_N(2)  OUT  = M_C_CS_N<2>
  W48  DDR2_CS_N(5)  OUT  = M_C_CS_N<5>
  W50  DDR2_MA(14)  OUT  = M_C_MA<14>
  W52  DDR2_BA(0)  OUT  = M_C_BA<0>
  W54  DDR2_CLK_DN(1)  OUT  = M_C_CLK_DN<1>
  W56  DDR2_CLK_DN(3)  OUT  = M_C_CLK_DN<3>
  W58  DDR2_MA(3)  OUT  = M_C_MA<3>
  W60  DDR1_MA(8)  OUT  = M_B_MA<8>
  W62  DDR1_ALERT_N  IN  = M_B_ALERT_N
  W64  VCCD012(32)  POWER  = PVDDQ_ABC
  W66  RSVD(258)  BI  = TP_CPU0_RSVD_258
  W68  VSS(951)  GROUND  = GND
  W70  DDR2_DQS_DP(2)  BI  = M_C_DQS_DP<2>
  W72  DDR2_DQ(16)  BI  = M_C_DQ<16>
  W74  VSS(950)  GROUND  = GND
  W76  DDR2_DQ(11)  BI  = M_C_DQ<11>
  W78  VSS(949)  GROUND  = GND
  W80  DDR0_DQ(20)  BI  = M_A_DQ<20>
  W82  VSS(948)  GROUND  = GND
  W84  DDR0_DQ(9)  BI  = M_A_DQ<9>
  W86  DDR0_DQ(8)  BI  = M_A_DQ<8>
  Y1  UPI0_TX_DN(3)  OUT  = UPI_CPU0_CPU1_P0P0_DN<16>
  Y3  UPI0_TX_DP(2)  OUT  = UPI_CPU0_CPU1_P0P0_DP<17>
  Y5  VSS(945)  GROUND  = GND
  Y7  VSS(943)  GROUND  = GND
  Y9  VSS(942)  GROUND  = GND
  Y11  BPM_N(5)  BI  = TP_XDP_CPU0_OBSDATA_A3_MBP5_N
  Y13  TRST_N  IN  = XDP_CPU_TRST_N
  Y15  VSS(947)  GROUND  = GND
  Y17  VSS(946)  GROUND  = GND
  Y19  UPI1_RX_DP(17)  IN  = UPI_CPU1_CPU0_P1P1_DP<2>
  Y21  UPI1_RX_DN(18)  IN  = UPI_CPU1_CPU0_P1P1_DN<1>
  Y23  RSVD(257)  BI  = FM_CPU0_RC_ERROR_N
  Y25  DDR1_DQ(59)  BI  = M_B_DQ<59>
  Y27  DDR1_DQS_DP(7)  BI  = M_B_DQS_DP<7>
  Y29  DDR1_DQ(61)  BI  = M_B_DQ<61>
  Y31  DDR2_DQ(43)  BI  = M_C_DQ<43>
  Y33  DDR2_DQS_DP(5)  BI  = M_C_DQS_DP<5>
  Y35  DDR2_DQ(45)  BI  = M_C_DQ<45>
  Y37  DDR2_DQ(35)  BI  = M_C_DQ<35>
  Y39  DDR2_DQS_DP(4)  BI  = M_C_DQS_DP<4>
  Y41  DDR2_DQ(37)  BI  = M_C_DQ<37>
  Y43  DDR012_RCOMP(0)  BI  = A_CPU0_ABC_RCOMP0
  Y45  VCCD012(33)  POWER  = PVDDQ_ABC
  Y47  VCCD012(34)  POWER  = PVDDQ_ABC
  Y49  VCCD012(35)  POWER  = PVDDQ_ABC
  Y51  VCCD012(36)  POWER  = PVDDQ_ABC
  Y53  VCCD012(37)  POWER  = PVDDQ_ABC
  Y55  VCCD012(38)  POWER  = PVDDQ_ABC
  Y57  VCCD012(39)  POWER  = PVDDQ_ABC
  Y59  VCCD012(40)  POWER  = PVDDQ_ABC
  Y61  VCCD012(41)  POWER  = PVDDQ_ABC
  Y63  VCCD012(42)  POWER  = PVDDQ_ABC
  Y65  RSVD(256)  BI  = TP_CPU0_RSVD_256
  Y67  VSS(944)  GROUND  = GND
  Y69  DDR2_DQS_DN(2)  BI  = M_C_DQS_DN<2>
  Y71  VSS(941)  GROUND  = GND
  Y73  VSS(940)  GROUND  = GND
  Y75  DDR2_DQ(15)  BI  = M_C_DQ<15>
  Y77  DDR2_DQ(10)  BI  = M_C_DQ<10>
  Y79  VSS(939)  GROUND  = GND
  Y81  VSS(938)  GROUND  = GND
  Y83  VSS(937)  GROUND  = GND
  Y85  VSS(936)  GROUND  = GND

U6F1  PCA9617  IC  pkg SSOP  page 99
  1  VCCA  POWER  = PVCCIO_CPU0
  2  SCLA  IN  = SMB_DDR_ABC_SCL_G
  3  SDAA  IN  = SMB_DDR_ABC_SDA_G
  5  EN  IN  = TP_SMB_DDR_ABC_EN
  6  SDAB  OUT  = SMB_DDR_ABC_VPP_SDA_R
  7  SCLB  OUT  = SMB_DDR_ABC_VPP_SCL_R
  8  VCCB  POWER  = PVPP_ABC

U6M1  74CBTLV1G125  IC  pkg SMLF  page 113
  1  OE_N  IN  = FM_CPU1_PKGID1
  2  A  IN  = P1V8_MCP_CPU1
  4  B  OUT  = JTAG_MCP_CPU1_TDI_R

U6W1  TCA9555PWR-GP  pkg DISCRET-GC1  page 247
  1  \int#\  OUT  = PCA9555_INT_N
  2  A1  IN  = PCA9555_A1
  3  A2  IN  = PCA9555_A2
  4  P00  BI  = LED_POSTCODE_0_R
  5  P01  BI  = LED_POSTCODE_1_R
  6  P02  BI  = LED_POSTCODE_2_R
  7  P03  BI  = LED_POSTCODE_3_R
  8  P04  BI  = LED_POSTCODE_4_R
  9  P05  BI  = LED_POSTCODE_5_R
  10  P06  BI  = LED_POSTCODE_6_R
  11  P07  BI  = LED_POSTCODE_7_R
  12  GND  POWER  = GND
  13  P10  BI  = FM_DEBUG_RST_BTN_N
  14  P11  BI  = FP_PWR_BTN_R_N
  15  P12  BI  = PWRGD_SYS_PWROK
  16  P13  BI  = RST_PLTRST_N
  17  P14  BI  = PWRGD_DSW_PWROK
  18  P15  BI  = FM_CPU_CATERR_MSMI_LVT3_N
  19  P16  BI  = FM_SLPS3_N
  20  P17  BI  = FM_UART_SWITCH_N
  21  A0  IN  = PCA9555_A0
  22  SCL  UNSPEC  = SMB_DEBUG_STBY_LVC3_SCL
  23  SDA  UNSPEC  = SMB_DEBUG_STBY_LVC3_SDA
  24  VCC  POWER  = P3V3_STBY

U6W2  TCA9517DGKR-GP  pkg DISCRET-G8  page 247
  1  VCCA  POWER  = P3V3_STBY
  2  SCLA  UNSPEC  = SMB_PMBUS_BMC_STBY_LVC3_SCL_R1
  3  SDAA  UNSPEC  = SMB_PMBUS_BMC_STBY_LVC3_SDA_R1
  4  GND  POWER  = GND
  5  EN  UNSPEC  = HSC_SMBUS_SWITCH_EN
  6  SDAB  UNSPEC  = SMB_BMC_PMBUS_STBY_LVC3_SDA
  7  SCLB  UNSPEC  = SMB_BMC_PMBUS_STBY_LVC3_SCL
  8  VCCB  POWER  = P3V3_STBY

U6W3  AT24C64  IC  pkg SOICLF  page 247
  1  A0  IN  = PU_ID_EEPROM_A0
  2  A1  IN  = GND
  3  A2  IN  = GND
  5  SDA  BI  = SMB_HOST_STBY_LVC3_SDA_R3
  6  SCL  IN  = SMB_HOST_STBY_LVC3_SCL_R3
  7  WP  IN  = PD_ID_EEPROM_WP

U6W4  TTL1G126_A  74HC1G126 IC  pkg SOT  page 176
  1  OE  IN  = DEBUG_CARD2_PRSNT
  2  A  IN  = SPA_MID_DBG2_RX
  4  Y  OUT  = SPA_MID_DBG2_RX_BUF

U6W5  TTL1G126_A  74HC1G126 IC  pkg SOT  page 176
  1  OE  IN  = DEBUG_CARD2_PRSNT
  2  A  IN  = SPA_MID_DBG_TX
  4  Y  OUT  = SPA_MID_DBG2_TX_R

U6W6  TTL1G126_A  74HC1G126 IC  pkg SOT  page 176
  1  OE  IN  = SPA_MID_DBG1_TX_EN
  2  A  IN  = SPA_MID_DBG_TX
  4  Y  OUT  = SPA_MID_DBG1_TX_R

U6W11  PCA9554PWR-GP  pkg DISCRET-G1  page 164
  1  A0  IN  = PCA9554_A0
  2  A1  IN  = PCA9554_A1
  3  A2  IN  = PCA9554_A2
  4  P0  BI  = FM_MB_SLOT_ID0
  5  P1  BI  = FM_MB_SLOT_ID1
  6  P2  BI  = FM_MB_SLOT_ID2
  7  P3  BI  = FM_CPU_BMC_INIT
  8  GND  POWER  = GND
  9  P4  BI  = NC
  10  P5  BI  = NC
  11  P6  BI  = NC
  12  P7  BI  = NC
  13  \int#\  OUT  = PCA9554_INT_N
  14  SCL  UNSPEC  = SMB_SENSOR_STBY_LVC3_SCL
  15  SDA  IN  = SMB_SENSOR_STBY_LVC3_SDA
  16  VCC  POWER  = P3V3_STBY

U6W12  NC7SB3157  IC  pkg SMLF  page 176
  1  B1  UNSPEC  = SPA_MID_DBG2_RX_BUF
  2  GND  UNSPEC  = GND
  3  B0  UNSPEC  = SPA_MID_DBG1_RX
  4  A  UNSPEC  = SPA_MID_DBG_RX
  5  VCC  UNSPEC  = P3V3_STBY
  6  S  UNSPEC  = DEBUG_CARD2_PRSNT
